FILE_TYPE=LIBRARY_PARTS;
primitive 'SCONN3_D53458001','SCONN3_D53458001_SM','SCONN3_D53458001_SM1';
  pin
    'IO1':
      PIN_NUMBER='(1)';
      BIDIRECTIONAL='TRUE';
      INPUT_LOAD='(-0.01,0.01)';
      OUTPUT_LOAD='(1.0,-1.0)';
    'IO2':
      PIN_NUMBER='(2)';
      BIDIRECTIONAL='TRUE';
      INPUT_LOAD='(-0.01,0.01)';
      OUTPUT_LOAD='(1.0,-1.0)';
    'IO3':
      PIN_NUMBER='(3)';
      BIDIRECTIONAL='TRUE';
      INPUT_LOAD='(-0.01,0.01)';
      OUTPUT_LOAD='(1.0,-1.0)';
  end_pin;
  body
    PART_NAME='SCONN3_D53458001';
    PHYS_DES_PREFIX='J';
  end_body;
end_primitive;

END.
